(kicad_pcb
	(version 20260206)
	(generator "pcbnew")
	(generator_version "10.0")
	(general
		(thickness 1.6)
		(legacy_teardrops no)
	)
	(paper "A4")
	(title_block
		(title "01162023_DA0F0TEBIF0_F0T_Expander_BD_F_brd_V02_OCP.brd")
		(comment 1 "Grand Teton / footprints 3041-3047 of 9728")
	)
	(layers
		(0 "F.Cu" signal "TOP")
		(4 "In1.Cu" signal "GND")
		(6 "In2.Cu" signal "VCC")
		(8 "In3.Cu" signal "VCC1")
		(10 "In4.Cu" signal "GND1")
		(12 "In5.Cu" signal "IN1")
		(14 "In6.Cu" signal "GND2")
		(16 "In7.Cu" signal "IN2")
		(18 "In8.Cu" signal "GND3")
		(20 "In9.Cu" signal "IN3")
		(22 "In10.Cu" signal "GND4")
		(24 "In11.Cu" signal "IN4")
		(26 "In12.Cu" signal "GND5")
		(28 "In13.Cu" signal "IN5")
		(30 "In14.Cu" signal "GND6")
		(32 "In15.Cu" signal "IN6")
		(34 "In16.Cu" signal "GND7")
		(2 "B.Cu" signal "BOTTOM")
		(9 "F.Adhes" user "F.Adhesive")
		(11 "B.Adhes" user "B.Adhesive")
		(13 "F.Paste" user "Package Geometry/Pastemask Top")
		(15 "B.Paste" user "Package Geometry/Pastemask Bottom")
		(5 "F.SilkS" user "Ref Des/Silkscreen Top")
		(7 "B.SilkS" user "Ref Des/Silkscreen Bottom")
		(1 "F.Mask" user "Board Geometry/Soldermask Top")
		(3 "B.Mask" user "Board Geometry/Soldermask Bottom")
		(17 "Dwgs.User" user "User.Drawings")
		(19 "Cmts.User" user "User.Comments")
		(21 "Eco1.User" user "User.Eco1")
		(23 "Eco2.User" user "User.Eco2")
		(25 "Edge.Cuts" user "Board Geometry/Outline")
		(27 "Margin" user)
		(31 "F.CrtYd" user "Package Geometry/Place Bound Top")
		(29 "B.CrtYd" user "Package Geometry/Place Bound Bottom")
		(35 "F.Fab" user "Ref Des/Assembly Top")
		(33 "B.Fab" user "Ref Des/Assembly Bottom")
	)
	(footprint ""
		(layer "F.Cu")
		(at 400.567906 -52.035456 180)
		(property "Reference" "R872"
			(at 0 0 180)
			(layer "F.SilkS")
			(hide yes)
			(effects
				(font
					(size 1.27 1.27)
				)
			)
		)
		(property "Value" ""
			(at 0 0 180)
			(layer "F.Fab")
			(effects
				(font
					(size 1.27 1.27)
				)
			)
		)
		(duplicate_pad_numbers_are_jumpers no)
		(fp_line
			(start 0.7874 0.4064)
			(end -0.7874 0.4064)
			(stroke
				(width 0.1524)
				(type default)
			)
			(layer "F.SilkS")
		)
		(fp_line
			(start 0.7874 -0.4064)
			(end 0.7874 0.4064)
			(stroke
				(width 0.1524)
				(type default)
			)
			(layer "F.SilkS")
		)
		(fp_line
			(start -0.7874 0.4064)
			(end -0.7874 -0.4064)
			(stroke
				(width 0.1524)
				(type default)
			)
			(layer "F.SilkS")
		)
		(fp_line
			(start -0.7874 -0.4064)
			(end 0.7874 -0.4064)
			(stroke
				(width 0.1524)
				(type default)
			)
			(layer "F.SilkS")
		)
		(fp_line
			(start 0.67945 0.3048)
			(end 0.120396 0.3048)
			(stroke
				(width 0.1)
				(type default)
			)
			(layer "F.Fab")
		)
		(fp_line
			(start 0.67945 -0.3048)
			(end 0.67945 0.3048)
			(stroke
				(width 0.1)
				(type default)
			)
			(layer "F.Fab")
		)
		(fp_line
			(start 0.12065 -0.2794)
			(end 0.12065 -0.3048)
			(stroke
				(width 0.1)
				(type default)
			)
			(layer "F.Fab")
		)
		(fp_line
			(start 0.12065 -0.3048)
			(end 0.67945 -0.3048)
			(stroke
				(width 0.1)
				(type default)
			)
			(layer "F.Fab")
		)
		(fp_line
			(start 0.120396 0.3048)
			(end 0.120396 0.2794)
			(stroke
				(width 0.1)
				(type default)
			)
			(layer "F.Fab")
		)
		(fp_line
			(start 0.120396 0.2794)
			(end -0.12065 0.2794)
			(stroke
				(width 0.1)
				(type default)
			)
			(layer "F.Fab")
		)
		(fp_line
			(start -0.12065 0.3048)
			(end -0.67945 0.3048)
			(stroke
				(width 0.1)
				(type default)
			)
			(layer "F.Fab")
		)
		(fp_line
			(start -0.12065 0.2794)
			(end -0.12065 0.3048)
			(stroke
				(width 0.1)
				(type default)
			)
			(layer "F.Fab")
		)
		(fp_line
			(start -0.12065 -0.2794)
			(end 0.12065 -0.2794)
			(stroke
				(width 0.1)
				(type default)
			)
			(layer "F.Fab")
		)
		(fp_line
			(start -0.12065 -0.305054)
			(end -0.12065 -0.2794)
			(stroke
				(width 0.1)
				(type default)
			)
			(layer "F.Fab")
		)
		(fp_line
			(start -0.67945 0.3048)
			(end -0.67945 -0.305054)
			(stroke
				(width 0.1)
				(type default)
			)
			(layer "F.Fab")
		)
		(fp_line
			(start -0.67945 -0.305054)
			(end -0.12065 -0.305054)
			(stroke
				(width 0.1)
				(type default)
			)
			(layer "F.Fab")
		)
		(pad "1" smd circle
			(at -0.40005 0 180)
			(size 0 0)
			(layers "F.Cu" "F.Mask" "F.Paste")
			(net "P3V3_AUX")
		)
		(pad "2" smd circle
			(at 0.40005 0 180)
			(size 0 0)
			(layers "F.Cu" "F.Mask" "F.Paste")
			(net "PWRGD_P12V_SSD13")
		)
	)
	(footprint ""
		(layer "F.Cu")
		(at 184.837832 -343.952322 90)
		(property "Reference" "C2533"
			(at 0 0 90)
			(layer "F.SilkS")
			(hide yes)
			(effects
				(font
					(size 1.27 1.27)
				)
			)
		)
		(property "Value" ""
			(at 0 0 90)
			(layer "F.Fab")
			(effects
				(font
					(size 1.27 1.27)
				)
			)
		)
		(duplicate_pad_numbers_are_jumpers no)
		(fp_line
			(start 0.299974 -0.150114)
			(end 0.299974 0.150114)
			(stroke
				(width 0.1)
				(type default)
			)
			(layer "F.Fab")
		)
		(fp_line
			(start -0.299974 -0.150114)
			(end 0.299974 -0.150114)
			(stroke
				(width 0.1)
				(type default)
			)
			(layer "F.Fab")
		)
		(fp_line
			(start 0.299974 0.150114)
			(end -0.299974 0.150114)
			(stroke
				(width 0.1)
				(type default)
			)
			(layer "F.Fab")
		)
		(fp_line
			(start -0.299974 0.150114)
			(end -0.299974 -0.150114)
			(stroke
				(width 0.1)
				(type default)
			)
			(layer "F.Fab")
		)
		(pad "1" smd rect
			(at -0.2667 0 90)
			(size 0.3048 0.381)
			(layers "F.Cu" "F.Mask" "F.Paste")
			(net "P5E_PEX1_STN4_TX_DN<69>")
		)
		(pad "2" smd rect
			(at 0.2667 0 90)
			(size 0.3048 0.381)
			(layers "F.Cu" "F.Mask" "F.Paste")
			(net "P5E_PEX1_STN4_TX_C_DN<69>")
		)
	)
	(footprint ""
		(layer "F.Cu")
		(at 210.439 -198.247 180)
		(property "Reference" "R1525"
			(at 0 0 180)
			(layer "F.SilkS")
			(hide yes)
			(effects
				(font
					(size 1.27 1.27)
				)
			)
		)
		(property "Value" ""
			(at 0 0 180)
			(layer "F.Fab")
			(effects
				(font
					(size 1.27 1.27)
				)
			)
		)
		(duplicate_pad_numbers_are_jumpers no)
		(fp_line
			(start 0.7874 0.4064)
			(end -0.7874 0.4064)
			(stroke
				(width 0.1524)
				(type default)
			)
			(layer "F.SilkS")
		)
		(fp_line
			(start 0.7874 -0.4064)
			(end 0.7874 0.4064)
			(stroke
				(width 0.1524)
				(type default)
			)
			(layer "F.SilkS")
		)
		(fp_line
			(start -0.7874 0.4064)
			(end -0.7874 -0.4064)
			(stroke
				(width 0.1524)
				(type default)
			)
			(layer "F.SilkS")
		)
		(fp_line
			(start -0.7874 -0.4064)
			(end 0.7874 -0.4064)
			(stroke
				(width 0.1524)
				(type default)
			)
			(layer "F.SilkS")
		)
		(fp_line
			(start 0.67945 0.3048)
			(end 0.120396 0.3048)
			(stroke
				(width 0.1)
				(type default)
			)
			(layer "F.Fab")
		)
		(fp_line
			(start 0.67945 -0.3048)
			(end 0.67945 0.3048)
			(stroke
				(width 0.1)
				(type default)
			)
			(layer "F.Fab")
		)
		(fp_line
			(start 0.12065 -0.2794)
			(end 0.12065 -0.3048)
			(stroke
				(width 0.1)
				(type default)
			)
			(layer "F.Fab")
		)
		(fp_line
			(start 0.12065 -0.3048)
			(end 0.67945 -0.3048)
			(stroke
				(width 0.1)
				(type default)
			)
			(layer "F.Fab")
		)
		(fp_line
			(start 0.120396 0.3048)
			(end 0.120396 0.2794)
			(stroke
				(width 0.1)
				(type default)
			)
			(layer "F.Fab")
		)
		(fp_line
			(start 0.120396 0.2794)
			(end -0.12065 0.2794)
			(stroke
				(width 0.1)
				(type default)
			)
			(layer "F.Fab")
		)
		(fp_line
			(start -0.12065 0.3048)
			(end -0.67945 0.3048)
			(stroke
				(width 0.1)
				(type default)
			)
			(layer "F.Fab")
		)
		(fp_line
			(start -0.12065 0.2794)
			(end -0.12065 0.3048)
			(stroke
				(width 0.1)
				(type default)
			)
			(layer "F.Fab")
		)
		(fp_line
			(start -0.12065 -0.2794)
			(end 0.12065 -0.2794)
			(stroke
				(width 0.1)
				(type default)
			)
			(layer "F.Fab")
		)
		(fp_line
			(start -0.12065 -0.305054)
			(end -0.12065 -0.2794)
			(stroke
				(width 0.1)
				(type default)
			)
			(layer "F.Fab")
		)
		(fp_line
			(start -0.67945 0.3048)
			(end -0.67945 -0.305054)
			(stroke
				(width 0.1)
				(type default)
			)
			(layer "F.Fab")
		)
		(fp_line
			(start -0.67945 -0.305054)
			(end -0.12065 -0.305054)
			(stroke
				(width 0.1)
				(type default)
			)
			(layer "F.Fab")
		)
		(pad "1" smd circle
			(at -0.40005 0 180)
			(size 0 0)
			(layers "F.Cu" "F.Mask" "F.Paste")
			(net "SMB_NIC6_R_SDA")
		)
		(pad "2" smd circle
			(at 0.40005 0 180)
			(size 0 0)
			(layers "F.Cu" "F.Mask" "F.Paste")
			(net "P1V2_AUX")
		)
	)
	(footprint ""
		(layer "F.Cu")
		(at 33.040066 -256.634234 180)
		(property "Reference" "C3050"
			(at 0 0 180)
			(layer "F.SilkS")
			(hide yes)
			(effects
				(font
					(size 1.27 1.27)
				)
			)
		)
		(property "Value" ""
			(at 0 0 180)
			(layer "F.Fab")
			(effects
				(font
					(size 1.27 1.27)
				)
			)
		)
		(duplicate_pad_numbers_are_jumpers no)
		(fp_line
			(start 1.2954 0.5842)
			(end -1.2954 0.5842)
			(stroke
				(width 0.1524)
				(type default)
			)
			(layer "F.SilkS")
		)
		(fp_line
			(start 1.2954 -0.5842)
			(end 1.2954 0.5842)
			(stroke
				(width 0.1524)
				(type default)
			)
			(layer "F.SilkS")
		)
		(fp_line
			(start -1.2954 0.5842)
			(end -1.2954 -0.5842)
			(stroke
				(width 0.1524)
				(type default)
			)
			(layer "F.SilkS")
		)
		(fp_line
			(start -1.2954 -0.5842)
			(end 1.2954 -0.5842)
			(stroke
				(width 0.1524)
				(type default)
			)
			(layer "F.SilkS")
		)
		(fp_line
			(start 1.1938 0.4064)
			(end 0.8636 0.4064)
			(stroke
				(width 0.1)
				(type default)
			)
			(layer "F.Fab")
		)
		(fp_line
			(start 1.1938 -0.4064)
			(end 1.1938 0.4064)
			(stroke
				(width 0.1)
				(type default)
			)
			(layer "F.Fab")
		)
		(fp_line
			(start 0.8636 0.4572)
			(end -0.8636 0.4572)
			(stroke
				(width 0.1)
				(type default)
			)
			(layer "F.Fab")
		)
		(fp_line
			(start 0.8636 0.4064)
			(end 0.8636 0.4572)
			(stroke
				(width 0.1)
				(type default)
			)
			(layer "F.Fab")
		)
		(fp_line
			(start 0.8636 -0.4064)
			(end 1.1938 -0.4064)
			(stroke
				(width 0.1)
				(type default)
			)
			(layer "F.Fab")
		)
		(fp_line
			(start 0.8636 -0.4572)
			(end 0.8636 -0.4064)
			(stroke
				(width 0.1)
				(type default)
			)
			(layer "F.Fab")
		)
		(fp_line
			(start -0.8636 0.4572)
			(end -0.8636 0.4064)
			(stroke
				(width 0.1)
				(type default)
			)
			(layer "F.Fab")
		)
		(fp_line
			(start -0.8636 0.4064)
			(end -1.1938 0.4064)
			(stroke
				(width 0.1)
				(type default)
			)
			(layer "F.Fab")
		)
		(fp_line
			(start -0.8636 -0.4064)
			(end -0.8636 -0.4572)
			(stroke
				(width 0.1)
				(type default)
			)
			(layer "F.Fab")
		)
		(fp_line
			(start -0.8636 -0.4572)
			(end 0.8636 -0.4572)
			(stroke
				(width 0.1)
				(type default)
			)
			(layer "F.Fab")
		)
		(fp_line
			(start -1.1938 0.4064)
			(end -1.1938 -0.4064)
			(stroke
				(width 0.1)
				(type default)
			)
			(layer "F.Fab")
		)
		(fp_line
			(start -1.1938 -0.4064)
			(end -0.8636 -0.4064)
			(stroke
				(width 0.1)
				(type default)
			)
			(layer "F.Fab")
		)
		(pad "1" smd rect
			(at -0.7366 0 90)
			(size 0.7112 0.8128)
			(layers "F.Cu" "F.Mask" "F.Paste")
			(net "PCEPLL5_VDDA18_PEX0_R")
		)
		(pad "2" smd rect
			(at 0.7366 0 90)
			(size 0.7112 0.8128)
			(layers "F.Cu" "F.Mask" "F.Paste")
			(net "GND")
		)
	)
	(footprint ""
		(layer "F.Cu")
		(at 204.472286 -373.65559 90)
		(property "Reference" "PC2"
			(at 0 0 90)
			(layer "F.SilkS")
			(hide yes)
			(effects
				(font
					(size 1.27 1.27)
				)
			)
		)
		(property "Value" ""
			(at 0 0 90)
			(layer "F.Fab")
			(effects
				(font
					(size 1.27 1.27)
				)
			)
		)
		(duplicate_pad_numbers_are_jumpers no)
		(fp_line
			(start 0.7874 -0.4064)
			(end 0.7874 0.4064)
			(stroke
				(width 0.1524)
				(type default)
			)
			(layer "F.SilkS")
		)
		(fp_line
			(start -0.7874 -0.4064)
			(end 0.7874 -0.4064)
			(stroke
				(width 0.1524)
				(type default)
			)
			(layer "F.SilkS")
		)
		(fp_line
			(start 0.7874 0.4064)
			(end -0.7874 0.4064)
			(stroke
				(width 0.1524)
				(type default)
			)
			(layer "F.SilkS")
		)
		(fp_line
			(start -0.7874 0.4064)
			(end -0.7874 -0.4064)
			(stroke
				(width 0.1524)
				(type default)
			)
			(layer "F.SilkS")
		)
		(fp_line
			(start -0.12065 -0.305054)
			(end -0.12065 -0.2794)
			(stroke
				(width 0.1)
				(type default)
			)
			(layer "F.Fab")
		)
		(fp_line
			(start -0.67945 -0.305054)
			(end -0.12065 -0.305054)
			(stroke
				(width 0.1)
				(type default)
			)
			(layer "F.Fab")
		)
		(fp_line
			(start 0.67945 -0.3048)
			(end 0.67945 0.3048)
			(stroke
				(width 0.1)
				(type default)
			)
			(layer "F.Fab")
		)
		(fp_line
			(start 0.12065 -0.3048)
			(end 0.67945 -0.3048)
			(stroke
				(width 0.1)
				(type default)
			)
			(layer "F.Fab")
		)
		(fp_line
			(start 0.12065 -0.2794)
			(end 0.12065 -0.3048)
			(stroke
				(width 0.1)
				(type default)
			)
			(layer "F.Fab")
		)
		(fp_line
			(start -0.12065 -0.2794)
			(end 0.12065 -0.2794)
			(stroke
				(width 0.1)
				(type default)
			)
			(layer "F.Fab")
		)
		(fp_line
			(start 0.120396 0.2794)
			(end -0.12065 0.2794)
			(stroke
				(width 0.1)
				(type default)
			)
			(layer "F.Fab")
		)
		(fp_line
			(start -0.12065 0.2794)
			(end -0.12065 0.3048)
			(stroke
				(width 0.1)
				(type default)
			)
			(layer "F.Fab")
		)
		(fp_line
			(start 0.67945 0.3048)
			(end 0.120396 0.3048)
			(stroke
				(width 0.1)
				(type default)
			)
			(layer "F.Fab")
		)
		(fp_line
			(start 0.120396 0.3048)
			(end 0.120396 0.2794)
			(stroke
				(width 0.1)
				(type default)
			)
			(layer "F.Fab")
		)
		(fp_line
			(start -0.12065 0.3048)
			(end -0.67945 0.3048)
			(stroke
				(width 0.1)
				(type default)
			)
			(layer "F.Fab")
		)
		(fp_line
			(start -0.67945 0.3048)
			(end -0.67945 -0.305054)
			(stroke
				(width 0.1)
				(type default)
			)
			(layer "F.Fab")
		)
		(pad "1" smd circle
			(at -0.40005 0 90)
			(size 0 0)
			(layers "F.Cu" "F.Mask" "F.Paste")
			(net "HSC_VINSEN")
		)
		(pad "2" smd circle
			(at 0.40005 0 90)
			(size 0 0)
			(layers "F.Cu" "F.Mask" "F.Paste")
			(net "AGND_HSC")
		)
	)
	(footprint ""
		(layer "F.Cu")
		(at 441.36564 -304.036476 90)
		(property "Reference" "R4184"
			(at 0 0 90)
			(layer "F.SilkS")
			(hide yes)
			(effects
				(font
					(size 1.27 1.27)
				)
			)
		)
		(property "Value" ""
			(at 0 0 90)
			(layer "F.Fab")
			(effects
				(font
					(size 1.27 1.27)
				)
			)
		)
		(duplicate_pad_numbers_are_jumpers no)
		(fp_line
			(start 0.7874 -0.4064)
			(end 0.7874 0.4064)
			(stroke
				(width 0.1524)
				(type default)
			)
			(layer "F.SilkS")
		)
		(fp_line
			(start -0.7874 -0.4064)
			(end 0.7874 -0.4064)
			(stroke
				(width 0.1524)
				(type default)
			)
			(layer "F.SilkS")
		)
		(fp_line
			(start 0.7874 0.4064)
			(end -0.7874 0.4064)
			(stroke
				(width 0.1524)
				(type default)
			)
			(layer "F.SilkS")
		)
		(fp_line
			(start -0.7874 0.4064)
			(end -0.7874 -0.4064)
			(stroke
				(width 0.1524)
				(type default)
			)
			(layer "F.SilkS")
		)
		(fp_line
			(start -0.12065 -0.305054)
			(end -0.12065 -0.2794)
			(stroke
				(width 0.1)
				(type default)
			)
			(layer "F.Fab")
		)
		(fp_line
			(start -0.67945 -0.305054)
			(end -0.12065 -0.305054)
			(stroke
				(width 0.1)
				(type default)
			)
			(layer "F.Fab")
		)
		(fp_line
			(start 0.67945 -0.3048)
			(end 0.67945 0.3048)
			(stroke
				(width 0.1)
				(type default)
			)
			(layer "F.Fab")
		)
		(fp_line
			(start 0.12065 -0.3048)
			(end 0.67945 -0.3048)
			(stroke
				(width 0.1)
				(type default)
			)
			(layer "F.Fab")
		)
		(fp_line
			(start 0.12065 -0.2794)
			(end 0.12065 -0.3048)
			(stroke
				(width 0.1)
				(type default)
			)
			(layer "F.Fab")
		)
		(fp_line
			(start -0.12065 -0.2794)
			(end 0.12065 -0.2794)
			(stroke
				(width 0.1)
				(type default)
			)
			(layer "F.Fab")
		)
		(fp_line
			(start 0.120396 0.2794)
			(end -0.12065 0.2794)
			(stroke
				(width 0.1)
				(type default)
			)
			(layer "F.Fab")
		)
		(fp_line
			(start -0.12065 0.2794)
			(end -0.12065 0.3048)
			(stroke
				(width 0.1)
				(type default)
			)
			(layer "F.Fab")
		)
		(fp_line
			(start 0.67945 0.3048)
			(end 0.120396 0.3048)
			(stroke
				(width 0.1)
				(type default)
			)
			(layer "F.Fab")
		)
		(fp_line
			(start 0.120396 0.3048)
			(end 0.120396 0.2794)
			(stroke
				(width 0.1)
				(type default)
			)
			(layer "F.Fab")
		)
		(fp_line
			(start -0.12065 0.3048)
			(end -0.67945 0.3048)
			(stroke
				(width 0.1)
				(type default)
			)
			(layer "F.Fab")
		)
		(fp_line
			(start -0.67945 0.3048)
			(end -0.67945 -0.305054)
			(stroke
				(width 0.1)
				(type default)
			)
			(layer "F.Fab")
		)
		(pad "1" smd circle
			(at -0.40005 0 90)
			(size 0 0)
			(layers "F.Cu" "F.Mask" "F.Paste")
			(net "GND")
		)
		(pad "2" smd circle
			(at 0.40005 0 90)
			(size 0 0)
			(layers "F.Cu" "F.Mask" "F.Paste")
			(net "PEX3_EXT_GPIO_LATCH_N")
		)
	)
	(footprint ""
		(layer "F.Cu")
		(at 106.614214 -217.079576)
		(property "Reference" "PC286"
			(at 0 0 0)
			(layer "F.SilkS")
			(hide yes)
			(effects
				(font
					(size 1.27 1.27)
				)
			)
		)
		(property "Value" ""
			(at 0 0 0)
			(layer "F.Fab")
			(effects
				(font
					(size 1.27 1.27)
				)
			)
		)
		(duplicate_pad_numbers_are_jumpers no)
		(fp_line
			(start -1.524 -0.762)
			(end 1.524 -0.762)
			(stroke
				(width 0.1524)
				(type default)
			)
			(layer "F.SilkS")
		)
		(fp_line
			(start -1.524 0.762)
			(end -1.524 -0.762)
			(stroke
				(width 0.1524)
				(type default)
			)
			(layer "F.SilkS")
		)
		(fp_line
			(start 1.524 -0.762)
			(end 1.524 0.762)
			(stroke
				(width 0.1524)
				(type default)
			)
			(layer "F.SilkS")
		)
		(fp_line
			(start 1.524 0.762)
			(end -1.524 0.762)
			(stroke
				(width 0.1524)
				(type default)
			)
			(layer "F.SilkS")
		)
		(fp_line
			(start -1.1049 -0.724916)
			(end -1.1049 0.724916)
			(stroke
				(width 0.1)
				(type default)
			)
			(layer "F.Fab")
		)
		(fp_line
			(start -1.1049 0.724916)
			(end 1.1049 0.724916)
			(stroke
				(width 0.1)
				(type default)
			)
			(layer "F.Fab")
		)
		(fp_line
			(start 1.1049 -0.724916)
			(end -1.1049 -0.724916)
			(stroke
				(width 0.1)
				(type default)
			)
			(layer "F.Fab")
		)
		(fp_line
			(start 1.1049 0.724916)
			(end 1.1049 -0.724916)
			(stroke
				(width 0.1)
				(type default)
			)
			(layer "F.Fab")
		)
		(pad "1" smd rect
			(at -0.889 0 180)
			(size 1.016 1.27)
			(layers "F.Cu" "F.Mask" "F.Paste")
			(net "SW_P12V_P1V8_PEX_FLT")
		)
		(pad "2" smd rect
			(at 0.889 0 180)
			(size 1.016 1.27)
			(layers "F.Cu" "F.Mask" "F.Paste")
			(net "GND")
		)
	)
)
